(kicad_pcb
	(version 20260206)
	(generator "pcbnew")
	(generator_version "10.0")
	(general
		(thickness 1.6)
		(legacy_teardrops no)
	)
	(paper "A4")
	(title_block
		(title "04192023_DAF0TMB3IC0_F0TG_MB_C_brd_V02_OCP.brd")
		(comment 1 "Grand Teton / footprints 106-110 of 8354")
	)
	(layers
		(0 "F.Cu" signal "TOP")
		(4 "In1.Cu" signal "GND")
		(6 "In2.Cu" signal "IN1")
		(8 "In3.Cu" signal "GND1")
		(10 "In4.Cu" signal "IN2")
		(12 "In5.Cu" signal "GND2")
		(14 "In6.Cu" signal "IN3")
		(16 "In7.Cu" signal "GND3")
		(18 "In8.Cu" signal "VCC")
		(20 "In9.Cu" signal "VCC1")
		(22 "In10.Cu" signal "GND4")
		(24 "In11.Cu" signal "IN4")
		(26 "In12.Cu" signal "GND5")
		(28 "In13.Cu" signal "IN5")
		(30 "In14.Cu" signal "GND6")
		(32 "In15.Cu" signal "IN6")
		(34 "In16.Cu" signal "GND7")
		(2 "B.Cu" signal "BOTTOM")
		(9 "F.Adhes" user "F.Adhesive")
		(11 "B.Adhes" user "B.Adhesive")
		(13 "F.Paste" user "Package Geometry/Pastemask Top")
		(15 "B.Paste" user "Package Geometry/Pastemask Bottom")
		(5 "F.SilkS" user "Ref Des/Silkscreen Top")
		(7 "B.SilkS" user "Ref Des/Silkscreen Bottom")
		(1 "F.Mask" user "Board Geometry/Soldermask Top")
		(3 "B.Mask" user "Board Geometry/Soldermask Bottom")
		(17 "Dwgs.User" user "User.Drawings")
		(19 "Cmts.User" user "User.Comments")
		(21 "Eco1.User" user "User.Eco1")
		(23 "Eco2.User" user "User.Eco2")
		(25 "Edge.Cuts" user "Board Geometry/Outline")
		(27 "Margin" user)
		(31 "F.CrtYd" user "Package Geometry/Place Bound Top")
		(29 "B.CrtYd" user "Package Geometry/Place Bound Bottom")
		(35 "F.Fab" user "Ref Des/Assembly Top")
		(33 "B.Fab" user "Ref Des/Assembly Bottom")
	)
	(footprint ""
		(layer "F.Cu")
		(at 431.970688 -351.140268)
		(property "Reference" "PU23"
			(at 5.206238 -1.0922 90)
			(unlocked yes)
			(layer "F.SilkS")
			(effects
				(font
					(size 0.7874 0.5842)
					(thickness 0.1524)
				)
				(justify left)
			)
		)
		(property "Value" ""
			(at 0 0 0)
			(layer "F.Fab")
			(effects
				(font
					(size 1.27 1.27)
				)
			)
		)
		(duplicate_pad_numbers_are_jumpers no)
		(fp_line
			(start -2.500122 -2.999994)
			(end -2.24409 -2.999994)
			(stroke
				(width 0.1524)
				(type default)
			)
			(layer "F.SilkS")
		)
		(fp_line
			(start -2.500122 -2.529078)
			(end -2.500122 -2.999994)
			(stroke
				(width 0.1524)
				(type default)
			)
			(layer "F.SilkS")
		)
		(fp_line
			(start -2.500122 0.6604)
			(end -2.500122 0.229108)
			(stroke
				(width 0.1524)
				(type default)
			)
			(layer "F.SilkS")
		)
		(fp_line
			(start -2.500122 2.999994)
			(end -2.500122 2.339594)
			(stroke
				(width 0.1524)
				(type default)
			)
			(layer "F.SilkS")
		)
		(fp_line
			(start -2.2987 2.999994)
			(end -2.500122 2.999994)
			(stroke
				(width 0.1524)
				(type default)
			)
			(layer "F.SilkS")
		)
		(fp_line
			(start 2.31394 -2.999994)
			(end 2.500122 -2.999994)
			(stroke
				(width 0.1524)
				(type default)
			)
			(layer "F.SilkS")
		)
		(fp_line
			(start 2.500122 -2.999994)
			(end 2.500122 -2.44348)
			(stroke
				(width 0.1524)
				(type default)
			)
			(layer "F.SilkS")
		)
		(fp_line
			(start 2.500122 2.339594)
			(end 2.500122 2.999994)
			(stroke
				(width 0.1524)
				(type default)
			)
			(layer "F.SilkS")
		)
		(fp_line
			(start 2.500122 2.999994)
			(end 2.2987 2.999994)
			(stroke
				(width 0.1524)
				(type default)
			)
			(layer "F.SilkS")
		)
		(fp_poly
			(pts
				(xy -3.43535 -2.660142) (xy -2.99339 -3.102356) (xy -2.771902 -2.438908)
			)
			(stroke
				(width 0)
				(type default)
			)
			(fill yes)
			(layer "F.SilkS")
		)
		(fp_line
			(start -2.500122 -2.999994)
			(end 2.500122 -2.999994)
			(stroke
				(width 0.1)
				(type default)
			)
			(layer "F.Fab")
		)
		(fp_line
			(start -2.500122 2.999994)
			(end -2.500122 -2.999994)
			(stroke
				(width 0.1)
				(type default)
			)
			(layer "F.Fab")
		)
		(fp_line
			(start 2.500122 -2.999994)
			(end 2.500122 2.999994)
			(stroke
				(width 0.1)
				(type default)
			)
			(layer "F.Fab")
		)
		(fp_line
			(start 2.500122 2.999994)
			(end -2.500122 2.999994)
			(stroke
				(width 0.1)
				(type default)
			)
			(layer "F.Fab")
		)
		(fp_poly
			(pts
				(xy -4.218432 -2.783078) (xy -4.218432 -1.767078) (xy -3.202432 -2.275078)
			)
			(stroke
				(width 0)
				(type default)
			)
			(fill yes)
			(layer "F.Fab")
		)
		(pad "1" smd rect
			(at -2.400046 -2.275078 90)
			(size 0.2286 0.6096)
			(layers "F.Cu" "F.Mask" "F.Paste")
			(net "PVDD11_S3_P0_VOS2")
		)
		(pad "2" smd rect
			(at -2.400046 -1.82499 90)
			(size 0.2286 0.6096)
			(layers "F.Cu" "F.Mask" "F.Paste")
			(net "GND")
		)
		(pad "3" smd rect
			(at -2.400046 -1.374902 90)
			(size 0.2286 0.6096)
			(layers "F.Cu" "F.Mask" "F.Paste")
			(net "PVDD11_S3_P0_VCC2")
		)
		(pad "4" smd rect
			(at -2.400046 -0.925068 90)
			(size 0.2286 0.6096)
			(layers "F.Cu" "F.Mask" "F.Paste")
			(net "PVDD11_S3_P0_PVCC")
		)
		(pad "5" smd rect
			(at -2.400046 -0.47498 90)
			(size 0.2286 0.6096)
			(layers "F.Cu" "F.Mask" "F.Paste")
			(net "GND")
		)
		(pad "6" smd rect
			(at -2.400046 -0.024892 90)
			(size 0.2286 0.6096)
			(layers "F.Cu" "F.Mask" "F.Paste")
			(net "NC_PVDD11_S3_P0_GL1_2")
		)
		(pad "7_9-20_24" smd circle
			(at 0 1.150112 90)
			(size 0 0)
			(layers "F.Cu" "F.Mask" "F.Paste")
			(net "GND")
		)
		(pad "10_19" smd rect
			(at 0 2.899918 90)
			(size 0.6096 4.318)
			(layers "F.Cu" "F.Mask" "F.Paste")
			(net "SW_PVDD11_S3_P0_SW2")
		)
		(pad "25_29" smd rect
			(at 1.549908 -1.279906 270)
			(size 2.0574 2.3114)
			(layers "F.Cu" "F.Mask" "F.Paste")
			(net "SW_P12V_AUX_PVDD11_S3_P0_FLT")
		)
		(pad "30" smd rect
			(at 2.05994 -2.899918)
			(size 0.2286 0.6096)
			(layers "F.Cu" "F.Mask" "F.Paste")
			(net "SW_P12V_AUX_PVDD11_S3_P0_FLT")
		)
		(pad "31" smd rect
			(at 1.610106 -2.899918)
			(size 0.2286 0.6096)
			(layers "F.Cu" "F.Mask" "F.Paste")
			(net "NC_PVDD11_S3_P0_DNC2")
		)
		(pad "32" smd rect
			(at 1.160018 -2.899918)
			(size 0.2286 0.6096)
			(layers "F.Cu" "F.Mask" "F.Paste")
			(net "SW_PVDD11_S3_P0_PH2")
		)
		(pad "33" smd rect
			(at 0.70993 -2.899918)
			(size 0.2286 0.6096)
			(layers "F.Cu" "F.Mask" "F.Paste")
			(net "SW_PVDD11_S3_P0_BOOT2")
		)
		(pad "34" smd rect
			(at 0.260096 -2.899918)
			(size 0.2286 0.6096)
			(layers "F.Cu" "F.Mask" "F.Paste")
			(net "PVDD11_S3_P0_PWM2")
		)
		(pad "35" smd rect
			(at -0.189992 -2.899918)
			(size 0.2286 0.6096)
			(layers "F.Cu" "F.Mask" "F.Paste")
			(net "PVDD11_S3_P0_VCC2")
		)
		(pad "36" smd rect
			(at -0.64008 -2.899918)
			(size 0.2286 0.6096)
			(layers "F.Cu" "F.Mask" "F.Paste")
			(net "PVDD11_S3_P0_TEMP0")
		)
		(pad "37" smd rect
			(at -1.089914 -2.899918)
			(size 0.2286 0.6096)
			(layers "F.Cu" "F.Mask" "F.Paste")
			(net "PVDD11_S3_P0_LSET2")
		)
		(pad "38" smd rect
			(at -1.540002 -2.899918)
			(size 0.2286 0.6096)
			(layers "F.Cu" "F.Mask" "F.Paste")
			(net "PVDD11_S3_P0_IMON2")
		)
		(pad "39" smd rect
			(at -1.99009 -2.899918)
			(size 0.2286 0.6096)
			(layers "F.Cu" "F.Mask" "F.Paste")
			(net "PVDD11_S3_P0_VCCS")
		)
		(pad "40" smd rect
			(at -0.87503 -1.27508)
			(size 1.7526 1.9558)
			(layers "F.Cu" "F.Mask" "F.Paste")
			(net "GND")
		)
		(pad "41" smd rect
			(at -1.525016 0.249936 270)
			(size 0.3048 0.4572)
			(layers "F.Cu" "F.Mask" "F.Paste")
			(net "NC_PVDD11_S3_P0_GL2_2")
		)
		(zone
			(layer "F.Cu")
			(hatch none 0.5)
			(connect_pads
				(clearance 0)
			)
			(min_thickness 0.25)
			(keepout
				(tracks not_allowed)
				(vias allowed)
				(pads allowed)
				(copperpour not_allowed)
				(footprints allowed)
			)
			(placement
				(enabled no)
				(sheetname "")
			)
			(fill
				(thermal_gap 0.5)
				(thermal_bridge_width 0.5)
				(island_removal_mode 0)
			)
			(polygon
				(pts
					(xy 429.470566 -348.584266) (xy 429.470566 -348.889574) (xy 434.47081 -348.889574) (xy 434.47081 -348.140274)
					(xy 434.180488 -348.140274) (xy 434.180488 -348.59595) (xy 429.760888 -348.59595) (xy 429.760888 -348.584266)
				)
			)
		)
		(zone
			(layer "F.Cu")
			(hatch none 0.5)
			(connect_pads
				(clearance 0)
			)
			(min_thickness 0.25)
			(keepout
				(tracks not_allowed)
				(vias allowed)
				(pads allowed)
				(copperpour not_allowed)
				(footprints allowed)
			)
			(placement
				(enabled no)
				(sheetname "")
			)
			(fill
				(thermal_gap 0.5)
				(thermal_bridge_width 0.5)
				(island_removal_mode 0)
			)
			(polygon
				(pts
					(xy 432.022758 -351.38868) (xy 432.022758 -353.444048) (xy 430.168558 -353.444048) (xy 430.168558 -353.203002)
					(xy 429.926242 -353.203002) (xy 429.926242 -353.684586) (xy 433.731162 -353.684586) (xy 433.731162 -353.499674)
					(xy 432.314096 -353.499674) (xy 432.314096 -351.340674) (xy 434.47081 -351.340674) (xy 434.47081 -351.090992)
					(xy 432.320446 -351.090992)
				)
			)
		)
	)
	(footprint ""
		(layer "F.Cu")
		(at 183.650128 -133.55701 -90)
		(property "Reference" "R196"
			(at 0 0 270)
			(layer "F.SilkS")
			(hide yes)
			(effects
				(font
					(size 1.27 1.27)
				)
			)
		)
		(property "Value" ""
			(at 0 0 270)
			(layer "F.Fab")
			(effects
				(font
					(size 1.27 1.27)
				)
			)
		)
		(duplicate_pad_numbers_are_jumpers no)
		(fp_line
			(start -0.7874 0.4064)
			(end -0.7874 -0.4064)
			(stroke
				(width 0.1524)
				(type default)
			)
			(layer "F.SilkS")
		)
		(fp_line
			(start 0.7874 0.4064)
			(end -0.7874 0.4064)
			(stroke
				(width 0.1524)
				(type default)
			)
			(layer "F.SilkS")
		)
		(fp_line
			(start -0.7874 -0.4064)
			(end 0.7874 -0.4064)
			(stroke
				(width 0.1524)
				(type default)
			)
			(layer "F.SilkS")
		)
		(fp_line
			(start 0.7874 -0.4064)
			(end 0.7874 0.4064)
			(stroke
				(width 0.1524)
				(type default)
			)
			(layer "F.SilkS")
		)
		(fp_line
			(start -0.67945 0.3048)
			(end -0.67945 -0.305054)
			(stroke
				(width 0.1)
				(type default)
			)
			(layer "F.Fab")
		)
		(fp_line
			(start -0.12065 0.3048)
			(end -0.67945 0.3048)
			(stroke
				(width 0.1)
				(type default)
			)
			(layer "F.Fab")
		)
		(fp_line
			(start 0.120396 0.3048)
			(end 0.120396 0.2794)
			(stroke
				(width 0.1)
				(type default)
			)
			(layer "F.Fab")
		)
		(fp_line
			(start 0.67945 0.3048)
			(end 0.120396 0.3048)
			(stroke
				(width 0.1)
				(type default)
			)
			(layer "F.Fab")
		)
		(fp_line
			(start -0.12065 0.2794)
			(end -0.12065 0.3048)
			(stroke
				(width 0.1)
				(type default)
			)
			(layer "F.Fab")
		)
		(fp_line
			(start 0.120396 0.2794)
			(end -0.12065 0.2794)
			(stroke
				(width 0.1)
				(type default)
			)
			(layer "F.Fab")
		)
		(fp_line
			(start -0.12065 -0.2794)
			(end 0.12065 -0.2794)
			(stroke
				(width 0.1)
				(type default)
			)
			(layer "F.Fab")
		)
		(fp_line
			(start 0.12065 -0.2794)
			(end 0.12065 -0.3048)
			(stroke
				(width 0.1)
				(type default)
			)
			(layer "F.Fab")
		)
		(fp_line
			(start 0.12065 -0.3048)
			(end 0.67945 -0.3048)
			(stroke
				(width 0.1)
				(type default)
			)
			(layer "F.Fab")
		)
		(fp_line
			(start 0.67945 -0.3048)
			(end 0.67945 0.3048)
			(stroke
				(width 0.1)
				(type default)
			)
			(layer "F.Fab")
		)
		(fp_line
			(start -0.67945 -0.305054)
			(end -0.12065 -0.305054)
			(stroke
				(width 0.1)
				(type default)
			)
			(layer "F.Fab")
		)
		(fp_line
			(start -0.12065 -0.305054)
			(end -0.12065 -0.2794)
			(stroke
				(width 0.1)
				(type default)
			)
			(layer "F.Fab")
		)
		(pad "1" smd circle
			(at -0.40005 0 270)
			(size 0 0)
			(layers "F.Cu" "F.Mask" "F.Paste")
			(net "CPU1_NV_SAVE_N")
		)
		(pad "2" smd circle
			(at 0.40005 0 270)
			(size 0 0)
			(layers "F.Cu" "F.Mask" "F.Paste")
			(net "FM_CPU1_NV_SAVE_N")
		)
	)
	(footprint ""
		(layer "F.Cu")
		(at 396.038324 -172.51934 90)
		(property "Reference" "PC593"
			(at 0 0 90)
			(layer "F.SilkS")
			(hide yes)
			(effects
				(font
					(size 1.27 1.27)
				)
			)
		)
		(property "Value" ""
			(at 0 0 90)
			(layer "F.Fab")
			(effects
				(font
					(size 1.27 1.27)
				)
			)
		)
		(duplicate_pad_numbers_are_jumpers no)
		(fp_line
			(start 0.7874 -0.4064)
			(end 0.7874 0.4064)
			(stroke
				(width 0.1524)
				(type default)
			)
			(layer "F.SilkS")
		)
		(fp_line
			(start -0.7874 -0.4064)
			(end 0.7874 -0.4064)
			(stroke
				(width 0.1524)
				(type default)
			)
			(layer "F.SilkS")
		)
		(fp_line
			(start 0.7874 0.4064)
			(end -0.7874 0.4064)
			(stroke
				(width 0.1524)
				(type default)
			)
			(layer "F.SilkS")
		)
		(fp_line
			(start -0.7874 0.4064)
			(end -0.7874 -0.4064)
			(stroke
				(width 0.1524)
				(type default)
			)
			(layer "F.SilkS")
		)
		(fp_line
			(start -0.12065 -0.305054)
			(end -0.12065 -0.2794)
			(stroke
				(width 0.1)
				(type default)
			)
			(layer "F.Fab")
		)
		(fp_line
			(start -0.67945 -0.305054)
			(end -0.12065 -0.305054)
			(stroke
				(width 0.1)
				(type default)
			)
			(layer "F.Fab")
		)
		(fp_line
			(start 0.67945 -0.3048)
			(end 0.67945 0.3048)
			(stroke
				(width 0.1)
				(type default)
			)
			(layer "F.Fab")
		)
		(fp_line
			(start 0.12065 -0.3048)
			(end 0.67945 -0.3048)
			(stroke
				(width 0.1)
				(type default)
			)
			(layer "F.Fab")
		)
		(fp_line
			(start 0.12065 -0.2794)
			(end 0.12065 -0.3048)
			(stroke
				(width 0.1)
				(type default)
			)
			(layer "F.Fab")
		)
		(fp_line
			(start -0.12065 -0.2794)
			(end 0.12065 -0.2794)
			(stroke
				(width 0.1)
				(type default)
			)
			(layer "F.Fab")
		)
		(fp_line
			(start 0.120396 0.2794)
			(end -0.12065 0.2794)
			(stroke
				(width 0.1)
				(type default)
			)
			(layer "F.Fab")
		)
		(fp_line
			(start -0.12065 0.2794)
			(end -0.12065 0.3048)
			(stroke
				(width 0.1)
				(type default)
			)
			(layer "F.Fab")
		)
		(fp_line
			(start 0.67945 0.3048)
			(end 0.120396 0.3048)
			(stroke
				(width 0.1)
				(type default)
			)
			(layer "F.Fab")
		)
		(fp_line
			(start 0.120396 0.3048)
			(end 0.120396 0.2794)
			(stroke
				(width 0.1)
				(type default)
			)
			(layer "F.Fab")
		)
		(fp_line
			(start -0.12065 0.3048)
			(end -0.67945 0.3048)
			(stroke
				(width 0.1)
				(type default)
			)
			(layer "F.Fab")
		)
		(fp_line
			(start -0.67945 0.3048)
			(end -0.67945 -0.305054)
			(stroke
				(width 0.1)
				(type default)
			)
			(layer "F.Fab")
		)
		(pad "1" smd circle
			(at -0.40005 0 90)
			(size 0 0)
			(layers "F.Cu" "F.Mask" "F.Paste")
			(net "SW_PVDDCR_SOC_P0_BOOT1_RC")
		)
		(pad "2" smd circle
			(at 0.40005 0 90)
			(size 0 0)
			(layers "F.Cu" "F.Mask" "F.Paste")
			(net "SW_PVDDCR_SOC_P0_PH1")
		)
	)
	(footprint ""
		(layer "F.Cu")
		(at 406.771348 -16.100298 90)
		(property "Reference" "C1560"
			(at 0 0 90)
			(layer "F.SilkS")
			(hide yes)
			(effects
				(font
					(size 1.27 1.27)
				)
			)
		)
		(property "Value" ""
			(at 0 0 90)
			(layer "F.Fab")
			(effects
				(font
					(size 1.27 1.27)
				)
			)
		)
		(duplicate_pad_numbers_are_jumpers no)
		(fp_line
			(start 0.299974 -0.150114)
			(end 0.299974 0.150114)
			(stroke
				(width 0.1)
				(type default)
			)
			(layer "F.Fab")
		)
		(fp_line
			(start -0.299974 -0.150114)
			(end 0.299974 -0.150114)
			(stroke
				(width 0.1)
				(type default)
			)
			(layer "F.Fab")
		)
		(fp_line
			(start 0.299974 0.150114)
			(end -0.299974 0.150114)
			(stroke
				(width 0.1)
				(type default)
			)
			(layer "F.Fab")
		)
		(fp_line
			(start -0.299974 0.150114)
			(end -0.299974 -0.150114)
			(stroke
				(width 0.1)
				(type default)
			)
			(layer "F.Fab")
		)
		(pad "1" smd rect
			(at -0.2667 0 90)
			(size 0.3048 0.381)
			(layers "F.Cu" "F.Mask" "F.Paste")
			(net "P5E_CPU0_G3_TX_C_DN<9>")
		)
		(pad "2" smd rect
			(at 0.2667 0 90)
			(size 0.3048 0.381)
			(layers "F.Cu" "F.Mask" "F.Paste")
			(net "P5E_CPU0_G3_TX_DN<9>")
		)
	)
	(footprint ""
		(layer "F.Cu")
		(at 282.985718 -390.49452 -90)
		(property "Reference" "R2626"
			(at 0 0 270)
			(layer "F.SilkS")
			(hide yes)
			(effects
				(font
					(size 1.27 1.27)
				)
			)
		)
		(property "Value" ""
			(at 0 0 270)
			(layer "F.Fab")
			(effects
				(font
					(size 1.27 1.27)
				)
			)
		)
		(duplicate_pad_numbers_are_jumpers no)
		(fp_line
			(start -0.7874 0.4064)
			(end -0.7874 -0.4064)
			(stroke
				(width 0.1524)
				(type default)
			)
			(layer "F.SilkS")
		)
		(fp_line
			(start 0.7874 0.4064)
			(end -0.7874 0.4064)
			(stroke
				(width 0.1524)
				(type default)
			)
			(layer "F.SilkS")
		)
		(fp_line
			(start -0.7874 -0.4064)
			(end 0.7874 -0.4064)
			(stroke
				(width 0.1524)
				(type default)
			)
			(layer "F.SilkS")
		)
		(fp_line
			(start 0.7874 -0.4064)
			(end 0.7874 0.4064)
			(stroke
				(width 0.1524)
				(type default)
			)
			(layer "F.SilkS")
		)
		(fp_line
			(start -0.67945 0.3048)
			(end -0.67945 -0.305054)
			(stroke
				(width 0.1)
				(type default)
			)
			(layer "F.Fab")
		)
		(fp_line
			(start -0.12065 0.3048)
			(end -0.67945 0.3048)
			(stroke
				(width 0.1)
				(type default)
			)
			(layer "F.Fab")
		)
		(fp_line
			(start 0.120396 0.3048)
			(end 0.120396 0.2794)
			(stroke
				(width 0.1)
				(type default)
			)
			(layer "F.Fab")
		)
		(fp_line
			(start 0.67945 0.3048)
			(end 0.120396 0.3048)
			(stroke
				(width 0.1)
				(type default)
			)
			(layer "F.Fab")
		)
		(fp_line
			(start -0.12065 0.2794)
			(end -0.12065 0.3048)
			(stroke
				(width 0.1)
				(type default)
			)
			(layer "F.Fab")
		)
		(fp_line
			(start 0.120396 0.2794)
			(end -0.12065 0.2794)
			(stroke
				(width 0.1)
				(type default)
			)
			(layer "F.Fab")
		)
		(fp_line
			(start -0.12065 -0.2794)
			(end 0.12065 -0.2794)
			(stroke
				(width 0.1)
				(type default)
			)
			(layer "F.Fab")
		)
		(fp_line
			(start 0.12065 -0.2794)
			(end 0.12065 -0.3048)
			(stroke
				(width 0.1)
				(type default)
			)
			(layer "F.Fab")
		)
		(fp_line
			(start 0.12065 -0.3048)
			(end 0.67945 -0.3048)
			(stroke
				(width 0.1)
				(type default)
			)
			(layer "F.Fab")
		)
		(fp_line
			(start 0.67945 -0.3048)
			(end 0.67945 0.3048)
			(stroke
				(width 0.1)
				(type default)
			)
			(layer "F.Fab")
		)
		(fp_line
			(start -0.67945 -0.305054)
			(end -0.12065 -0.305054)
			(stroke
				(width 0.1)
				(type default)
			)
			(layer "F.Fab")
		)
		(fp_line
			(start -0.12065 -0.305054)
			(end -0.12065 -0.2794)
			(stroke
				(width 0.1)
				(type default)
			)
			(layer "F.Fab")
		)
		(pad "1" smd circle
			(at -0.40005 0 270)
			(size 0 0)
			(layers "F.Cu" "F.Mask" "F.Paste")
			(net "SMB_P12V_HSC_TEMP_SCL")
		)
		(pad "2" smd circle
			(at 0.40005 0 270)
			(size 0 0)
			(layers "F.Cu" "F.Mask" "F.Paste")
			(net "SMB_P12V_HSC_SCL")
		)
	)
)
